FILE_TYPE = CONNECTIVITY;
{Allegro Design Entry HDL 16.6-p007 (v16-6-112F) 10/10/2012}
"PAGE_NUMBER" = 265;
0"NC";
END.
